# TIMECARD (Time Appliance Project (Time Card)) — schematic netlist excerpt (pin names and nets, part order shuffled) for the footprints in the layout excerpt that follows; sources: Cadence DE-HDL packaged netlist, KiCad conversion of R4006-B0001-02_R01.brd

R381  RESISTOR  4.7KOHM 1%  pkg SMC_0402R_H016  page 23 : \1\ = XP3R3V_FPGA ; \2\ = SMA1_SIG_IN_BF_EN_N

(kicad_pcb
	(version 20260206)
	(generator "pcbnew")
	(generator_version "10.0")
	(general
		(thickness 1.6)
		(legacy_teardrops no)
	)
	(paper "A4")
	(title_block
		(title "timecard-production-celestica-r4006 — R4006-B0001-02_R01.brd")
		(comment 1 "Time Appliance Project (Time Card) / footprints 596-596 of 1113")
	)
	(layers
		(0 "F.Cu" signal "TOP")
		(4 "In1.Cu" signal "L02_GND1")
		(6 "In2.Cu" signal "L03_SIG1")
		(8 "In3.Cu" signal "L04_GND2")
		(10 "In4.Cu" signal "L05_VCC1")
		(12 "In5.Cu" signal "L06_VCC2")
		(14 "In6.Cu" signal "L07_GND3")
		(16 "In7.Cu" signal "L08_SIG2")
		(18 "In8.Cu" signal "L09_GND4")
		(2 "B.Cu" signal "BOTTOM")
		(9 "F.Adhes" user "F.Adhesive")
		(11 "B.Adhes" user "B.Adhesive")
		(13 "F.Paste" user "Package Geometry/Pastemask Top")
		(15 "B.Paste" user "Package Geometry/Pastemask Bottom")
		(5 "F.SilkS" user "Ref Des/Silkscreen Top")
		(7 "B.SilkS" user "Ref Des/Silkscreen Bottom")
		(1 "F.Mask" user "Board Geometry/Soldermask Top")
		(3 "B.Mask" user "Board Geometry/Soldermask Bottom")
		(17 "Dwgs.User" user "User.Drawings")
		(19 "Cmts.User" user "User.Comments")
		(21 "Eco1.User" user "User.Eco1")
		(23 "Eco2.User" user "User.Eco2")
		(25 "Edge.Cuts" user "Board Geometry/Outline")
		(27 "Margin" user)
		(31 "F.CrtYd" user "Package Geometry/Place Bound Top")
		(29 "B.CrtYd" user "Package Geometry/Place Bound Bottom")
		(35 "F.Fab" user "Ref Des/Assembly Top")
		(33 "B.Fab" user "Ref Des/Assembly Bottom")
	)
	(footprint ""
		(layer "F.Cu")
		(at 13.068808 -57.2516 90)
		(property "Reference" "R381"
			(at -0.3556 -2.361438 90)
			(unlocked yes)
			(layer "F.SilkS")
			(effects
				(font
					(size 0.7874 0.5842)
					(thickness 0.1524)
				)
			)
		)
		(property "Value" "VAL*"
			(at 0.02032 2.13233 90)
			(unlocked yes)
			(layer "F.Fab")
			(hide yes)
			(effects
				(font
					(size 0.7874 0.5842)
					(thickness 0.1524)
				)
			)
		)
		(property "Device Type" "RESISTOR-G155-14701-01,4.7KOHMA"
			(at 0.008382 1.210564 90)
			(unlocked yes)
			(layer "F.Fab")
			(hide yes)
			(effects
				(font
					(size 0.7874 0.5842)
					(thickness 0.1524)
				)
			)
		)
		(property "User Part Number" "PARTNUM*"
			(at 0.02032 4.024884 90)
			(unlocked yes)
			(layer "Cmts.User")
			(hide yes)
			(effects
				(font
					(size 0.7874 0.5842)
					(thickness 0.1524)
				)
			)
		)
		(property "Tolerance" "TOL*"
			(at 0.044704 3.05435 90)
			(unlocked yes)
			(layer "Cmts.User")
			(hide yes)
			(effects
				(font
					(size 0.7874 0.5842)
					(thickness 0.1524)
				)
			)
		)
		(duplicate_pad_numbers_are_jumpers no)
		(fp_line
			(start 1.143 -0.5588)
			(end -1.143 -0.5588)
			(stroke
				(width 0.1)
				(type default)
			)
			(layer "F.SilkS")
		)
		(fp_line
			(start -1.143 -0.5588)
			(end -1.143 0.5588)
			(stroke
				(width 0.1)
				(type default)
			)
			(layer "F.SilkS")
		)
		(fp_line
			(start 1.143 0.5588)
			(end 1.143 -0.5588)
			(stroke
				(width 0.1)
				(type default)
			)
			(layer "F.SilkS")
		)
		(fp_line
			(start -1.143 0.5588)
			(end 1.143 0.5588)
			(stroke
				(width 0.1)
				(type default)
			)
			(layer "F.SilkS")
		)
		(fp_rect
			(start 1.143 0.5588)
			(end -1.143 -0.5588)
			(stroke
				(width 0)
				(type default)
			)
			(fill no)
			(layer "F.CrtYd")
		)
		(fp_line
			(start 0.508 -0.3048)
			(end -0.508 -0.3048)
			(stroke
				(width 0.1)
				(type default)
			)
			(layer "F.Fab")
		)
		(fp_line
			(start -0.508 -0.3048)
			(end -0.508 0.3048)
			(stroke
				(width 0.1)
				(type default)
			)
			(layer "F.Fab")
		)
		(fp_line
			(start 0.508 0.3048)
			(end 0.508 -0.3048)
			(stroke
				(width 0.1)
				(type default)
			)
			(layer "F.Fab")
		)
		(fp_line
			(start -0.508 0.3048)
			(end 0.508 0.3048)
			(stroke
				(width 0.1)
				(type default)
			)
			(layer "F.Fab")
		)
		(pad "1" smd rect
			(at -0.5334 0 90)
			(size 0.7112 0.6096)
			(layers "F.Cu" "F.Mask" "F.Paste")
			(net "XP3R3V_FPGA")
		)
		(pad "2" smd rect
			(at 0.5334 0 90)
			(size 0.7112 0.6096)
			(layers "F.Cu" "F.Mask" "F.Paste")
			(net "SMA1_SIG_IN_BF_EN_N")
		)
		(zone
			(layer "F.Cu")
			(hatch none 0.5)
			(connect_pads
				(clearance 0)
			)
			(min_thickness 0.25)
			(keepout
				(tracks not_allowed)
				(vias allowed)
				(pads allowed)
				(copperpour not_allowed)
				(footprints allowed)
			)
			(placement
				(enabled no)
				(sheetname "")
			)
			(fill
				(thermal_gap 0.5)
				(thermal_bridge_width 0.5)
				(island_removal_mode 0)
			)
			(polygon
				(pts
					(xy 13.373608 -57.3278) (xy 12.764008 -57.3278) (xy 12.764008 -57.1754) (xy 13.373608 -57.1754)
				)
			)
		)
		(zone
			(layer "F.Cu")
			(hatch none 0.5)
			(connect_pads
				(clearance 0)
			)
			(min_thickness 0.25)
			(keepout
				(tracks allowed)
				(vias not_allowed)
				(pads allowed)
				(copperpour not_allowed)
				(footprints allowed)
			)
			(placement
				(enabled no)
				(sheetname "")
			)
			(fill
				(thermal_gap 0.5)
				(thermal_bridge_width 0.5)
				(island_removal_mode 0)
			)
			(polygon
				(pts
					(xy 13.373608 -57.3278) (xy 12.764008 -57.3278) (xy 12.764008 -57.1754) (xy 13.373608 -57.1754)
				)
			)
		)
	)
)
